(kicad_pcb
	(version 20260206)
	(generator "pcbnew")
	(generator_version "10.0")
	(general
		(thickness 1.6)
		(legacy_teardrops no)
	)
	(paper "A4")
	(title_block
		(title "03242023_DA0F0TMBIJ0_F0T_Motherboard_J_brd_V01_OCP.brd")
		(comment 1 "Grand Teton / footprints 5546-5551 of 6105")
	)
	(layers
		(0 "F.Cu" signal "TOP")
		(4 "In1.Cu" signal "GND")
		(6 "In2.Cu" signal "IN1")
		(8 "In3.Cu" signal "GND1")
		(10 "In4.Cu" signal "IN2")
		(12 "In5.Cu" signal "GND2")
		(14 "In6.Cu" signal "IN3")
		(16 "In7.Cu" signal "GND3")
		(18 "In8.Cu" signal "VCC")
		(20 "In9.Cu" signal "VCC1")
		(22 "In10.Cu" signal "GND4")
		(24 "In11.Cu" signal "IN4")
		(26 "In12.Cu" signal "GND5")
		(28 "In13.Cu" signal "IN5")
		(30 "In14.Cu" signal "GND6")
		(32 "In15.Cu" signal "IN6")
		(34 "In16.Cu" signal "GND7")
		(2 "B.Cu" signal "BOTTOM")
		(9 "F.Adhes" user "F.Adhesive")
		(11 "B.Adhes" user "B.Adhesive")
		(13 "F.Paste" user "Package Geometry/Pastemask Top")
		(15 "B.Paste" user "Package Geometry/Pastemask Bottom")
		(5 "F.SilkS" user "Ref Des/Silkscreen Top")
		(7 "B.SilkS" user "Ref Des/Silkscreen Bottom")
		(1 "F.Mask" user "Board Geometry/Soldermask Top")
		(3 "B.Mask" user "Board Geometry/Soldermask Bottom")
		(17 "Dwgs.User" user "User.Drawings")
		(19 "Cmts.User" user "User.Comments")
		(21 "Eco1.User" user "User.Eco1")
		(23 "Eco2.User" user "User.Eco2")
		(25 "Edge.Cuts" user "Board Geometry/Outline")
		(27 "Margin" user)
		(31 "F.CrtYd" user "Package Geometry/Place Bound Top")
		(29 "B.CrtYd" user "Package Geometry/Place Bound Bottom")
		(35 "F.Fab" user "Ref Des/Assembly Top")
		(33 "B.Fab" user "Ref Des/Assembly Bottom")
	)
	(footprint ""
		(layer "B.Cu")
		(at 433.25288 -124.932948 90)
		(property "Reference" "PR4233"
			(at 0 0 90)
			(layer "B.SilkS")
			(hide yes)
			(effects
				(font
					(size 1.27 1.27)
				)
				(justify mirror)
			)
		)
		(property "Value" ""
			(at 0 0 90)
			(layer "B.Fab")
			(effects
				(font
					(size 1.27 1.27)
				)
				(justify mirror)
			)
		)
		(duplicate_pad_numbers_are_jumpers no)
		(fp_line
			(start 0.7874 -0.4064)
			(end -0.7874 -0.4064)
			(stroke
				(width 0.1524)
				(type default)
			)
			(layer "B.SilkS")
		)
		(fp_line
			(start -0.7874 -0.4064)
			(end -0.7874 0.4064)
			(stroke
				(width 0.1524)
				(type default)
			)
			(layer "B.SilkS")
		)
		(fp_line
			(start 0.7874 0.4064)
			(end 0.7874 -0.4064)
			(stroke
				(width 0.1524)
				(type default)
			)
			(layer "B.SilkS")
		)
		(fp_line
			(start -0.7874 0.4064)
			(end 0.7874 0.4064)
			(stroke
				(width 0.1524)
				(type default)
			)
			(layer "B.SilkS")
		)
		(fp_line
			(start 0.67945 -0.305054)
			(end 0.12065 -0.305054)
			(stroke
				(width 0.1)
				(type default)
			)
			(layer "B.Fab")
		)
		(fp_line
			(start 0.12065 -0.305054)
			(end 0.12065 -0.2794)
			(stroke
				(width 0.1)
				(type default)
			)
			(layer "B.Fab")
		)
		(fp_line
			(start -0.12065 -0.3048)
			(end -0.67945 -0.3048)
			(stroke
				(width 0.1)
				(type default)
			)
			(layer "B.Fab")
		)
		(fp_line
			(start -0.67945 -0.3048)
			(end -0.67945 0.3048)
			(stroke
				(width 0.1)
				(type default)
			)
			(layer "B.Fab")
		)
		(fp_line
			(start 0.12065 -0.2794)
			(end -0.12065 -0.2794)
			(stroke
				(width 0.1)
				(type default)
			)
			(layer "B.Fab")
		)
		(fp_line
			(start -0.12065 -0.2794)
			(end -0.12065 -0.3048)
			(stroke
				(width 0.1)
				(type default)
			)
			(layer "B.Fab")
		)
		(fp_line
			(start 0.12065 0.2794)
			(end 0.12065 0.3048)
			(stroke
				(width 0.1)
				(type default)
			)
			(layer "B.Fab")
		)
		(fp_line
			(start -0.120396 0.2794)
			(end 0.12065 0.2794)
			(stroke
				(width 0.1)
				(type default)
			)
			(layer "B.Fab")
		)
		(fp_line
			(start 0.67945 0.3048)
			(end 0.67945 -0.305054)
			(stroke
				(width 0.1)
				(type default)
			)
			(layer "B.Fab")
		)
		(fp_line
			(start 0.12065 0.3048)
			(end 0.67945 0.3048)
			(stroke
				(width 0.1)
				(type default)
			)
			(layer "B.Fab")
		)
		(fp_line
			(start -0.120396 0.3048)
			(end -0.120396 0.2794)
			(stroke
				(width 0.1)
				(type default)
			)
			(layer "B.Fab")
		)
		(fp_line
			(start -0.67945 0.3048)
			(end -0.120396 0.3048)
			(stroke
				(width 0.1)
				(type default)
			)
			(layer "B.Fab")
		)
		(pad "1" smd circle
			(at 0.40005 0 270)
			(size 0 0)
			(layers "B.Cu" "B.Mask" "B.Paste")
			(net "NC_PVCCD_HV_CPU0_ACSP5")
		)
		(pad "2" smd circle
			(at -0.40005 0 270)
			(size 0 0)
			(layers "B.Cu" "B.Mask" "B.Paste")
			(net "GND")
		)
	)
	(footprint ""
		(layer "B.Cu")
		(at 174.163228 -8.904478 180)
		(property "Reference" "R3112"
			(at 0 0 0)
			(layer "B.SilkS")
			(hide yes)
			(effects
				(font
					(size 1.27 1.27)
				)
				(justify mirror)
			)
		)
		(property "Value" ""
			(at 0 0 0)
			(layer "B.Fab")
			(effects
				(font
					(size 1.27 1.27)
				)
				(justify mirror)
			)
		)
		(duplicate_pad_numbers_are_jumpers no)
		(fp_line
			(start 0.7874 0.4064)
			(end 0.7874 -0.4064)
			(stroke
				(width 0.1524)
				(type default)
			)
			(layer "B.SilkS")
		)
		(fp_line
			(start 0.7874 -0.4064)
			(end -0.7874 -0.4064)
			(stroke
				(width 0.1524)
				(type default)
			)
			(layer "B.SilkS")
		)
		(fp_line
			(start -0.7874 0.4064)
			(end 0.7874 0.4064)
			(stroke
				(width 0.1524)
				(type default)
			)
			(layer "B.SilkS")
		)
		(fp_line
			(start -0.7874 -0.4064)
			(end -0.7874 0.4064)
			(stroke
				(width 0.1524)
				(type default)
			)
			(layer "B.SilkS")
		)
		(fp_line
			(start 0.67945 0.3048)
			(end 0.67945 -0.305054)
			(stroke
				(width 0.1)
				(type default)
			)
			(layer "B.Fab")
		)
		(fp_line
			(start 0.67945 -0.305054)
			(end 0.12065 -0.305054)
			(stroke
				(width 0.1)
				(type default)
			)
			(layer "B.Fab")
		)
		(fp_line
			(start 0.12065 0.3048)
			(end 0.67945 0.3048)
			(stroke
				(width 0.1)
				(type default)
			)
			(layer "B.Fab")
		)
		(fp_line
			(start 0.12065 0.2794)
			(end 0.12065 0.3048)
			(stroke
				(width 0.1)
				(type default)
			)
			(layer "B.Fab")
		)
		(fp_line
			(start 0.12065 -0.2794)
			(end -0.12065 -0.2794)
			(stroke
				(width 0.1)
				(type default)
			)
			(layer "B.Fab")
		)
		(fp_line
			(start 0.12065 -0.305054)
			(end 0.12065 -0.2794)
			(stroke
				(width 0.1)
				(type default)
			)
			(layer "B.Fab")
		)
		(fp_line
			(start -0.120396 0.3048)
			(end -0.120396 0.2794)
			(stroke
				(width 0.1)
				(type default)
			)
			(layer "B.Fab")
		)
		(fp_line
			(start -0.120396 0.2794)
			(end 0.12065 0.2794)
			(stroke
				(width 0.1)
				(type default)
			)
			(layer "B.Fab")
		)
		(fp_line
			(start -0.12065 -0.2794)
			(end -0.12065 -0.3048)
			(stroke
				(width 0.1)
				(type default)
			)
			(layer "B.Fab")
		)
		(fp_line
			(start -0.12065 -0.3048)
			(end -0.67945 -0.3048)
			(stroke
				(width 0.1)
				(type default)
			)
			(layer "B.Fab")
		)
		(fp_line
			(start -0.67945 0.3048)
			(end -0.120396 0.3048)
			(stroke
				(width 0.1)
				(type default)
			)
			(layer "B.Fab")
		)
		(fp_line
			(start -0.67945 -0.3048)
			(end -0.67945 0.3048)
			(stroke
				(width 0.1)
				(type default)
			)
			(layer "B.Fab")
		)
		(pad "1" smd circle
			(at 0.40005 0)
			(size 0 0)
			(layers "B.Cu" "B.Mask" "B.Paste")
			(net "I3C_BMC_SWB_SCL")
		)
		(pad "2" smd circle
			(at -0.40005 0)
			(size 0 0)
			(layers "B.Cu" "B.Mask" "B.Paste")
			(net "I3C_BMC_SWB_R_SCL")
		)
	)
	(footprint ""
		(layer "B.Cu")
		(at 91.161108 -190.705232 -90)
		(property "Reference" "R742"
			(at 0 0 90)
			(layer "B.SilkS")
			(hide yes)
			(effects
				(font
					(size 1.27 1.27)
				)
				(justify mirror)
			)
		)
		(property "Value" ""
			(at 0 0 90)
			(layer "B.Fab")
			(effects
				(font
					(size 1.27 1.27)
				)
				(justify mirror)
			)
		)
		(duplicate_pad_numbers_are_jumpers no)
		(fp_line
			(start -0.7874 0.4064)
			(end 0.7874 0.4064)
			(stroke
				(width 0.1524)
				(type default)
			)
			(layer "B.SilkS")
		)
		(fp_line
			(start 0.7874 0.4064)
			(end 0.7874 -0.4064)
			(stroke
				(width 0.1524)
				(type default)
			)
			(layer "B.SilkS")
		)
		(fp_line
			(start -0.7874 -0.4064)
			(end -0.7874 0.4064)
			(stroke
				(width 0.1524)
				(type default)
			)
			(layer "B.SilkS")
		)
		(fp_line
			(start 0.7874 -0.4064)
			(end -0.7874 -0.4064)
			(stroke
				(width 0.1524)
				(type default)
			)
			(layer "B.SilkS")
		)
		(fp_line
			(start -0.67945 0.3048)
			(end -0.120396 0.3048)
			(stroke
				(width 0.1)
				(type default)
			)
			(layer "B.Fab")
		)
		(fp_line
			(start -0.120396 0.3048)
			(end -0.120396 0.2794)
			(stroke
				(width 0.1)
				(type default)
			)
			(layer "B.Fab")
		)
		(fp_line
			(start 0.12065 0.3048)
			(end 0.67945 0.3048)
			(stroke
				(width 0.1)
				(type default)
			)
			(layer "B.Fab")
		)
		(fp_line
			(start 0.67945 0.3048)
			(end 0.67945 -0.305054)
			(stroke
				(width 0.1)
				(type default)
			)
			(layer "B.Fab")
		)
		(fp_line
			(start -0.120396 0.2794)
			(end 0.12065 0.2794)
			(stroke
				(width 0.1)
				(type default)
			)
			(layer "B.Fab")
		)
		(fp_line
			(start 0.12065 0.2794)
			(end 0.12065 0.3048)
			(stroke
				(width 0.1)
				(type default)
			)
			(layer "B.Fab")
		)
		(fp_line
			(start -0.12065 -0.2794)
			(end -0.12065 -0.3048)
			(stroke
				(width 0.1)
				(type default)
			)
			(layer "B.Fab")
		)
		(fp_line
			(start 0.12065 -0.2794)
			(end -0.12065 -0.2794)
			(stroke
				(width 0.1)
				(type default)
			)
			(layer "B.Fab")
		)
		(fp_line
			(start -0.67945 -0.3048)
			(end -0.67945 0.3048)
			(stroke
				(width 0.1)
				(type default)
			)
			(layer "B.Fab")
		)
		(fp_line
			(start -0.12065 -0.3048)
			(end -0.67945 -0.3048)
			(stroke
				(width 0.1)
				(type default)
			)
			(layer "B.Fab")
		)
		(fp_line
			(start 0.12065 -0.305054)
			(end 0.12065 -0.2794)
			(stroke
				(width 0.1)
				(type default)
			)
			(layer "B.Fab")
		)
		(fp_line
			(start 0.67945 -0.305054)
			(end 0.12065 -0.305054)
			(stroke
				(width 0.1)
				(type default)
			)
			(layer "B.Fab")
		)
		(pad "1" smd circle
			(at 0.40005 0 90)
			(size 0 0)
			(layers "B.Cu" "B.Mask" "B.Paste")
			(net "PVNN_TERM_CPU1")
		)
		(pad "2" smd circle
			(at -0.40005 0 90)
			(size 0 0)
			(layers "B.Cu" "B.Mask" "B.Paste")
			(net "JTAG_CPU1_MUX_GTL_TDO")
		)
	)
	(footprint ""
		(layer "B.Cu")
		(at 436.971694 -120.841008)
		(property "Reference" "R362"
			(at 0 0 0)
			(layer "B.SilkS")
			(hide yes)
			(effects
				(font
					(size 1.27 1.27)
				)
				(justify mirror)
			)
		)
		(property "Value" ""
			(at 0 0 0)
			(layer "B.Fab")
			(effects
				(font
					(size 1.27 1.27)
				)
				(justify mirror)
			)
		)
		(duplicate_pad_numbers_are_jumpers no)
		(fp_line
			(start -0.7874 -0.4064)
			(end -0.7874 0.4064)
			(stroke
				(width 0.1524)
				(type default)
			)
			(layer "B.SilkS")
		)
		(fp_line
			(start -0.7874 0.4064)
			(end 0.7874 0.4064)
			(stroke
				(width 0.1524)
				(type default)
			)
			(layer "B.SilkS")
		)
		(fp_line
			(start 0.7874 -0.4064)
			(end -0.7874 -0.4064)
			(stroke
				(width 0.1524)
				(type default)
			)
			(layer "B.SilkS")
		)
		(fp_line
			(start 0.7874 0.4064)
			(end 0.7874 -0.4064)
			(stroke
				(width 0.1524)
				(type default)
			)
			(layer "B.SilkS")
		)
		(fp_line
			(start -0.67945 -0.3048)
			(end -0.67945 0.3048)
			(stroke
				(width 0.1)
				(type default)
			)
			(layer "B.Fab")
		)
		(fp_line
			(start -0.67945 0.3048)
			(end -0.120396 0.3048)
			(stroke
				(width 0.1)
				(type default)
			)
			(layer "B.Fab")
		)
		(fp_line
			(start -0.12065 -0.3048)
			(end -0.67945 -0.3048)
			(stroke
				(width 0.1)
				(type default)
			)
			(layer "B.Fab")
		)
		(fp_line
			(start -0.12065 -0.2794)
			(end -0.12065 -0.3048)
			(stroke
				(width 0.1)
				(type default)
			)
			(layer "B.Fab")
		)
		(fp_line
			(start -0.120396 0.2794)
			(end 0.12065 0.2794)
			(stroke
				(width 0.1)
				(type default)
			)
			(layer "B.Fab")
		)
		(fp_line
			(start -0.120396 0.3048)
			(end -0.120396 0.2794)
			(stroke
				(width 0.1)
				(type default)
			)
			(layer "B.Fab")
		)
		(fp_line
			(start 0.12065 -0.305054)
			(end 0.12065 -0.2794)
			(stroke
				(width 0.1)
				(type default)
			)
			(layer "B.Fab")
		)
		(fp_line
			(start 0.12065 -0.2794)
			(end -0.12065 -0.2794)
			(stroke
				(width 0.1)
				(type default)
			)
			(layer "B.Fab")
		)
		(fp_line
			(start 0.12065 0.2794)
			(end 0.12065 0.3048)
			(stroke
				(width 0.1)
				(type default)
			)
			(layer "B.Fab")
		)
		(fp_line
			(start 0.12065 0.3048)
			(end 0.67945 0.3048)
			(stroke
				(width 0.1)
				(type default)
			)
			(layer "B.Fab")
		)
		(fp_line
			(start 0.67945 -0.305054)
			(end 0.12065 -0.305054)
			(stroke
				(width 0.1)
				(type default)
			)
			(layer "B.Fab")
		)
		(fp_line
			(start 0.67945 0.3048)
			(end 0.67945 -0.305054)
			(stroke
				(width 0.1)
				(type default)
			)
			(layer "B.Fab")
		)
		(pad "1" smd circle
			(at 0.40005 0 180)
			(size 0 0)
			(layers "B.Cu" "B.Mask" "B.Paste")
			(net "PWRGD_PVCCD_HV_CPU0")
		)
		(pad "2" smd circle
			(at -0.40005 0 180)
			(size 0 0)
			(layers "B.Cu" "B.Mask" "B.Paste")
			(net "PWRGD_PVCCD_HV_CPU0_R")
		)
	)
	(footprint ""
		(layer "B.Cu")
		(at 319.425066 -40.970454 -135)
		(property "Reference" "R696"
			(at 0 0 45)
			(layer "B.SilkS")
			(hide yes)
			(effects
				(font
					(size 1.27 1.27)
				)
				(justify mirror)
			)
		)
		(property "Value" ""
			(at 0 0 45)
			(layer "B.Fab")
			(effects
				(font
					(size 1.27 1.27)
				)
				(justify mirror)
			)
		)
		(duplicate_pad_numbers_are_jumpers no)
		(fp_line
			(start 0.787389 0.406267)
			(end 0.787389 -0.406267)
			(stroke
				(width 0.1524)
				(type default)
			)
			(layer "B.SilkS")
		)
		(fp_line
			(start 0.787389 -0.406267)
			(end -0.787389 -0.406267)
			(stroke
				(width 0.1524)
				(type default)
			)
			(layer "B.SilkS")
		)
		(fp_line
			(start -0.787389 0.406267)
			(end 0.787389 0.406267)
			(stroke
				(width 0.1524)
				(type default)
			)
			(layer "B.SilkS")
		)
		(fp_line
			(start -0.787389 -0.406267)
			(end -0.787389 0.406267)
			(stroke
				(width 0.1524)
				(type default)
			)
			(layer "B.SilkS")
		)
		(fp_line
			(start 0.679446 0.30479)
			(end 0.679446 -0.305149)
			(stroke
				(width 0.1)
				(type default)
			)
			(layer "B.Fab")
		)
		(fp_line
			(start 0.120515 0.30479)
			(end 0.679446 0.30479)
			(stroke
				(width 0.1)
				(type default)
			)
			(layer "B.Fab")
		)
		(fp_line
			(start 0.120695 0.279466)
			(end 0.120515 0.30479)
			(stroke
				(width 0.1)
				(type default)
			)
			(layer "B.Fab")
		)
		(fp_line
			(start 0.679446 -0.305149)
			(end 0.120695 -0.304969)
			(stroke
				(width 0.1)
				(type default)
			)
			(layer "B.Fab")
		)
		(fp_line
			(start -0.120515 0.30479)
			(end -0.120335 0.279466)
			(stroke
				(width 0.1)
				(type default)
			)
			(layer "B.Fab")
		)
		(fp_line
			(start -0.120335 0.279466)
			(end 0.120695 0.279466)
			(stroke
				(width 0.1)
				(type default)
			)
			(layer "B.Fab")
		)
		(fp_line
			(start 0.120695 -0.279466)
			(end -0.120695 -0.279466)
			(stroke
				(width 0.1)
				(type default)
			)
			(layer "B.Fab")
		)
		(fp_line
			(start 0.120695 -0.304969)
			(end 0.120695 -0.279466)
			(stroke
				(width 0.1)
				(type default)
			)
			(layer "B.Fab")
		)
		(fp_line
			(start -0.679446 0.30479)
			(end -0.120515 0.30479)
			(stroke
				(width 0.1)
				(type default)
			)
			(layer "B.Fab")
		)
		(fp_line
			(start -0.120695 -0.279466)
			(end -0.120515 -0.30479)
			(stroke
				(width 0.1)
				(type default)
			)
			(layer "B.Fab")
		)
		(fp_line
			(start -0.120515 -0.30479)
			(end -0.679446 -0.30479)
			(stroke
				(width 0.1)
				(type default)
			)
			(layer "B.Fab")
		)
		(fp_line
			(start -0.679446 -0.30479)
			(end -0.679446 0.30479)
			(stroke
				(width 0.1)
				(type default)
			)
			(layer "B.Fab")
		)
		(pad "1" smd circle
			(at 0.40005 0 45)
			(size 0 0)
			(layers "B.Cu" "B.Mask" "B.Paste")
			(net "P3V3_AUX")
		)
		(pad "2" smd circle
			(at -0.40005 0 45)
			(size 0 0)
			(layers "B.Cu" "B.Mask" "B.Paste")
			(net "RST_PCH_RSTBTN_R_N")
		)
	)
	(footprint ""
		(layer "B.Cu")
		(at 191.47409 -78.25613 -90)
		(property "Reference" "R3237"
			(at 0 0 90)
			(layer "B.SilkS")
			(hide yes)
			(effects
				(font
					(size 1.27 1.27)
				)
				(justify mirror)
			)
		)
		(property "Value" ""
			(at 0 0 90)
			(layer "B.Fab")
			(effects
				(font
					(size 1.27 1.27)
				)
				(justify mirror)
			)
		)
		(duplicate_pad_numbers_are_jumpers no)
		(fp_line
			(start -0.7874 0.4064)
			(end 0.7874 0.4064)
			(stroke
				(width 0.1524)
				(type default)
			)
			(layer "B.SilkS")
		)
		(fp_line
			(start 0.7874 0.4064)
			(end 0.7874 -0.4064)
			(stroke
				(width 0.1524)
				(type default)
			)
			(layer "B.SilkS")
		)
		(fp_line
			(start -0.7874 -0.4064)
			(end -0.7874 0.4064)
			(stroke
				(width 0.1524)
				(type default)
			)
			(layer "B.SilkS")
		)
		(fp_line
			(start 0.7874 -0.4064)
			(end -0.7874 -0.4064)
			(stroke
				(width 0.1524)
				(type default)
			)
			(layer "B.SilkS")
		)
		(fp_line
			(start -0.67945 0.3048)
			(end -0.120396 0.3048)
			(stroke
				(width 0.1)
				(type default)
			)
			(layer "B.Fab")
		)
		(fp_line
			(start -0.120396 0.3048)
			(end -0.120396 0.2794)
			(stroke
				(width 0.1)
				(type default)
			)
			(layer "B.Fab")
		)
		(fp_line
			(start 0.12065 0.3048)
			(end 0.67945 0.3048)
			(stroke
				(width 0.1)
				(type default)
			)
			(layer "B.Fab")
		)
		(fp_line
			(start 0.67945 0.3048)
			(end 0.67945 -0.305054)
			(stroke
				(width 0.1)
				(type default)
			)
			(layer "B.Fab")
		)
		(fp_line
			(start -0.120396 0.2794)
			(end 0.12065 0.2794)
			(stroke
				(width 0.1)
				(type default)
			)
			(layer "B.Fab")
		)
		(fp_line
			(start 0.12065 0.2794)
			(end 0.12065 0.3048)
			(stroke
				(width 0.1)
				(type default)
			)
			(layer "B.Fab")
		)
		(fp_line
			(start -0.12065 -0.2794)
			(end -0.12065 -0.3048)
			(stroke
				(width 0.1)
				(type default)
			)
			(layer "B.Fab")
		)
		(fp_line
			(start 0.12065 -0.2794)
			(end -0.12065 -0.2794)
			(stroke
				(width 0.1)
				(type default)
			)
			(layer "B.Fab")
		)
		(fp_line
			(start -0.67945 -0.3048)
			(end -0.67945 0.3048)
			(stroke
				(width 0.1)
				(type default)
			)
			(layer "B.Fab")
		)
		(fp_line
			(start -0.12065 -0.3048)
			(end -0.67945 -0.3048)
			(stroke
				(width 0.1)
				(type default)
			)
			(layer "B.Fab")
		)
		(fp_line
			(start 0.12065 -0.305054)
			(end 0.12065 -0.2794)
			(stroke
				(width 0.1)
				(type default)
			)
			(layer "B.Fab")
		)
		(fp_line
			(start 0.67945 -0.305054)
			(end 0.12065 -0.305054)
			(stroke
				(width 0.1)
				(type default)
			)
			(layer "B.Fab")
		)
		(pad "1" smd rect
			(at 0.40005 0 270)
			(size 0.4572 0.508)
			(layers "B.Cu" "B.Mask" "B.Paste")
			(net "OCP_SFF_RBT_ARB_OUT")
		)
		(pad "2" smd rect
			(at -0.40005 0 270)
			(size 0.4572 0.508)
			(layers "B.Cu" "B.Mask" "B.Paste")
			(net "OCP_SFF_RBT_ARB_IN_R")
		)
	)
)
